(kicad_pcb
	(version 20260206)
	(generator "pcbnew")
	(generator_version "10.0")
	(general
		(thickness 1.6)
		(legacy_teardrops no)
	)
	(paper "A4")
	(title_block
		(title "Bryce Canyon_IOM_IOC_16318-2_OCP.brd")
		(comment 1 "Bryce Canyon / footprints 406-413 of 1605")
	)
	(layers
		(0 "F.Cu" signal "TOP")
		(4 "In1.Cu" signal "L2GND")
		(6 "In2.Cu" signal "L3")
		(8 "In3.Cu" signal "L4VCC")
		(10 "In4.Cu" signal "L5VCC")
		(12 "In5.Cu" signal "L6")
		(14 "In6.Cu" signal "L7GND")
		(2 "B.Cu" signal "BOTTOM")
		(9 "F.Adhes" user "F.Adhesive")
		(11 "B.Adhes" user "B.Adhesive")
		(13 "F.Paste" user "Package Geometry/Pastemask Top")
		(15 "B.Paste" user "Package Geometry/Pastemask Bottom")
		(5 "F.SilkS" user "Ref Des/Silkscreen Top")
		(7 "B.SilkS" user "Ref Des/Silkscreen Bottom")
		(1 "F.Mask" user "Board Geometry/Soldermask Top")
		(3 "B.Mask" user "Board Geometry/Soldermask Bottom")
		(17 "Dwgs.User" user "User.Drawings")
		(19 "Cmts.User" user "User.Comments")
		(21 "Eco1.User" user "User.Eco1")
		(23 "Eco2.User" user "User.Eco2")
		(25 "Edge.Cuts" user "Board Geometry/Outline")
		(27 "Margin" user)
		(31 "F.CrtYd" user "Package Geometry/Place Bound Top")
		(29 "B.CrtYd" user "Package Geometry/Place Bound Bottom")
		(35 "F.Fab" user "Ref Des/Assembly Top")
		(33 "B.Fab" user "Ref Des/Assembly Bottom")
	)
	(footprint ""
		(layer "F.Cu")
		(at 192.5574 -48.2854)
		(property "Reference" "R658"
			(at 0 0 0)
			(layer "F.SilkS")
			(hide yes)
			(effects
				(font
					(size 1.27 1.27)
				)
			)
		)
		(property "Value" "4K7R2F-GP"
			(at 0.064008 -3.993896 0)
			(unlocked yes)
			(layer "F.Fab")
			(hide yes)
			(effects
				(font
					(size 1.016 1.016)
					(thickness 0.1524)
				)
			)
		)
		(property "Device Type" "R402H16"
			(at 0.064008 -5.517896 0)
			(unlocked yes)
			(layer "F.Fab")
			(hide yes)
			(effects
				(font
					(size 1.016 1.016)
					(thickness 0.1524)
				)
			)
		)
		(duplicate_pad_numbers_are_jumpers no)
		(fp_line
			(start -0.508 -0.9398)
			(end -0.508 0.9398)
			(stroke
				(width 0.1524)
				(type default)
			)
			(layer "F.SilkS")
		)
		(fp_line
			(start 0.508 -0.9398)
			(end -0.508 -0.9398)
			(stroke
				(width 0.1524)
				(type default)
			)
			(layer "F.SilkS")
		)
		(fp_rect
			(start -0.508 0.9398)
			(end 0.508 -0.9398)
			(stroke
				(width 0)
				(type default)
			)
			(fill no)
			(layer "F.CrtYd")
		)
		(fp_rect
			(start -0.508 0.9398)
			(end 0.508 -0.9398)
			(stroke
				(width 0)
				(type default)
			)
			(fill no)
			(layer "F.Fab")
		)
		(pad "1" smd custom
			(at 0 -0.4445)
			(size 0.1397 0.1397)
			(layers "F.Cu" "F.Mask" "F.Paste")
			(net "IOC_TRST_N")
			(options
				(clearance outline)
				(anchor circle)
			)
			(primitives
				(gr_poly
					(pts
						(arc
							(start -0.1778 -0.2794)
							(mid -0.249642 -0.249642)
							(end -0.2794 -0.1778)
						)
						(arc
							(start -0.2794 0.1778)
							(mid -0.249642 0.249642)
							(end -0.1778 0.2794)
						)
						(arc
							(start 0.1778 0.2794)
							(mid 0.249642 0.249642)
							(end 0.2794 0.1778)
						)
						(arc
							(start 0.2794 -0.1778)
							(mid 0.249642 -0.249642)
							(end 0.1778 -0.2794)
						)
					)
					(width 0)
					(fill yes)
				)
			)
		)
		(pad "2" smd custom
			(at 0 0.4445)
			(size 0.1397 0.1397)
			(layers "F.Cu" "F.Mask" "F.Paste")
			(net "GND")
			(options
				(clearance outline)
				(anchor circle)
			)
			(primitives
				(gr_poly
					(pts
						(arc
							(start -0.1778 -0.2794)
							(mid -0.249642 -0.249642)
							(end -0.2794 -0.1778)
						)
						(arc
							(start -0.2794 0.1778)
							(mid -0.249642 0.249642)
							(end -0.1778 0.2794)
						)
						(arc
							(start 0.1778 0.2794)
							(mid 0.249642 0.249642)
							(end 0.2794 0.1778)
						)
						(arc
							(start 0.2794 -0.1778)
							(mid 0.249642 -0.249642)
							(end 0.1778 -0.2794)
						)
					)
					(width 0)
					(fill yes)
				)
			)
		)
	)
	(footprint ""
		(layer "F.Cu")
		(at 88.788494 -128.989074 90)
		(property "Reference" "R420"
			(at 0 0 90)
			(layer "F.SilkS")
			(hide yes)
			(effects
				(font
					(size 1.27 1.27)
				)
			)
		)
		(property "Value" "4K7R2F-GP"
			(at 0.064008 -3.993896 90)
			(unlocked yes)
			(layer "F.Fab")
			(hide yes)
			(effects
				(font
					(size 1.016 1.016)
					(thickness 0.1524)
				)
			)
		)
		(property "Device Type" "R402H16"
			(at 0.064008 -5.517896 90)
			(unlocked yes)
			(layer "F.Fab")
			(hide yes)
			(effects
				(font
					(size 1.016 1.016)
					(thickness 0.1524)
				)
			)
		)
		(duplicate_pad_numbers_are_jumpers no)
		(fp_line
			(start 0.508 -0.9398)
			(end -0.508 -0.9398)
			(stroke
				(width 0.1524)
				(type default)
			)
			(layer "F.SilkS")
		)
		(fp_line
			(start -0.508 -0.9398)
			(end -0.508 0.9398)
			(stroke
				(width 0.1524)
				(type default)
			)
			(layer "F.SilkS")
		)
		(fp_rect
			(start -0.508 0.9398)
			(end 0.508 -0.9398)
			(stroke
				(width 0)
				(type default)
			)
			(fill no)
			(layer "F.CrtYd")
		)
		(fp_rect
			(start -0.508 0.9398)
			(end 0.508 -0.9398)
			(stroke
				(width 0)
				(type default)
			)
			(fill no)
			(layer "F.Fab")
		)
		(pad "1" smd custom
			(at 0 -0.4445 90)
			(size 0.1397 0.1397)
			(layers "F.Cu" "F.Mask" "F.Paste")
			(net "P3V3_STBY")
			(options
				(clearance outline)
				(anchor circle)
			)
			(primitives
				(gr_poly
					(pts
						(arc
							(start -0.1778 -0.2794)
							(mid -0.249642 -0.249642)
							(end -0.2794 -0.1778)
						)
						(arc
							(start -0.2794 0.1778)
							(mid -0.249642 0.249642)
							(end -0.1778 0.2794)
						)
						(arc
							(start 0.1778 0.2794)
							(mid 0.249642 0.249642)
							(end 0.2794 0.1778)
						)
						(arc
							(start 0.2794 -0.1778)
							(mid 0.249642 -0.249642)
							(end 0.1778 -0.2794)
						)
					)
					(width 0)
					(fill yes)
				)
			)
		)
		(pad "2" smd custom
			(at 0 0.4445 90)
			(size 0.1397 0.1397)
			(layers "F.Cu" "F.Mask" "F.Paste")
			(net "UART_SEL_MUX")
			(options
				(clearance outline)
				(anchor circle)
			)
			(primitives
				(gr_poly
					(pts
						(arc
							(start -0.1778 -0.2794)
							(mid -0.249642 -0.249642)
							(end -0.2794 -0.1778)
						)
						(arc
							(start -0.2794 0.1778)
							(mid -0.249642 0.249642)
							(end -0.1778 0.2794)
						)
						(arc
							(start 0.1778 0.2794)
							(mid 0.249642 0.249642)
							(end 0.2794 0.1778)
						)
						(arc
							(start 0.2794 -0.1778)
							(mid 0.249642 -0.249642)
							(end 0.1778 -0.2794)
						)
					)
					(width 0)
					(fill yes)
				)
			)
		)
	)
	(footprint ""
		(layer "F.Cu")
		(at 65.659 -172.085 180)
		(property "Reference" "R78"
			(at 0 0 180)
			(layer "F.SilkS")
			(hide yes)
			(effects
				(font
					(size 1.27 1.27)
				)
			)
		)
		(property "Value" "10KR2F-2-GP"
			(at 0.064008 -3.993896 180)
			(unlocked yes)
			(layer "F.Fab")
			(hide yes)
			(effects
				(font
					(size 1.016 1.016)
					(thickness 0.1524)
				)
			)
		)
		(property "Device Type" "R402H16"
			(at 0.064008 -5.517896 180)
			(unlocked yes)
			(layer "F.Fab")
			(hide yes)
			(effects
				(font
					(size 1.016 1.016)
					(thickness 0.1524)
				)
			)
		)
		(duplicate_pad_numbers_are_jumpers no)
		(fp_line
			(start 0.508 -0.9398)
			(end -0.508 -0.9398)
			(stroke
				(width 0.1524)
				(type default)
			)
			(layer "F.SilkS")
		)
		(fp_line
			(start -0.508 -0.9398)
			(end -0.508 0.9398)
			(stroke
				(width 0.1524)
				(type default)
			)
			(layer "F.SilkS")
		)
		(fp_rect
			(start -0.508 0.9398)
			(end 0.508 -0.9398)
			(stroke
				(width 0)
				(type default)
			)
			(fill no)
			(layer "F.CrtYd")
		)
		(fp_rect
			(start -0.508 0.9398)
			(end 0.508 -0.9398)
			(stroke
				(width 0)
				(type default)
			)
			(fill no)
			(layer "F.Fab")
		)
		(pad "1" smd custom
			(at 0 -0.4445 180)
			(size 0.1397 0.1397)
			(layers "F.Cu" "F.Mask" "F.Paste")
			(net "P3V3_STBY")
			(options
				(clearance outline)
				(anchor circle)
			)
			(primitives
				(gr_poly
					(pts
						(arc
							(start -0.1778 -0.2794)
							(mid -0.249642 -0.249642)
							(end -0.2794 -0.1778)
						)
						(arc
							(start -0.2794 0.1778)
							(mid -0.249642 0.249642)
							(end -0.1778 0.2794)
						)
						(arc
							(start 0.1778 0.2794)
							(mid 0.249642 0.249642)
							(end 0.2794 0.1778)
						)
						(arc
							(start 0.2794 -0.1778)
							(mid 0.249642 -0.249642)
							(end 0.1778 -0.2794)
						)
					)
					(width 0)
					(fill yes)
				)
			)
		)
		(pad "2" smd custom
			(at 0 0.4445 180)
			(size 0.1397 0.1397)
			(layers "F.Cu" "F.Mask" "F.Paste")
			(net "FM_TPM_PRSNT_N")
			(options
				(clearance outline)
				(anchor circle)
			)
			(primitives
				(gr_poly
					(pts
						(arc
							(start -0.1778 -0.2794)
							(mid -0.249642 -0.249642)
							(end -0.2794 -0.1778)
						)
						(arc
							(start -0.2794 0.1778)
							(mid -0.249642 0.249642)
							(end -0.1778 0.2794)
						)
						(arc
							(start 0.1778 0.2794)
							(mid 0.249642 0.249642)
							(end 0.2794 0.1778)
						)
						(arc
							(start 0.2794 -0.1778)
							(mid 0.249642 -0.249642)
							(end 0.1778 -0.2794)
						)
					)
					(width 0)
					(fill yes)
				)
			)
		)
	)
	(footprint ""
		(layer "F.Cu")
		(at 8.886698 -141.008862 90)
		(property "Reference" "R227"
			(at 0 0 90)
			(layer "F.SilkS")
			(hide yes)
			(effects
				(font
					(size 1.27 1.27)
				)
			)
		)
		(property "Value" "120R2F-GP"
			(at 0.064008 -3.993896 90)
			(unlocked yes)
			(layer "F.Fab")
			(hide yes)
			(effects
				(font
					(size 1.016 1.016)
					(thickness 0.1524)
				)
			)
		)
		(property "Device Type" "R402H16"
			(at 0.064008 -5.517896 90)
			(unlocked yes)
			(layer "F.Fab")
			(hide yes)
			(effects
				(font
					(size 1.016 1.016)
					(thickness 0.1524)
				)
			)
		)
		(duplicate_pad_numbers_are_jumpers no)
		(fp_line
			(start 0.508 -0.9398)
			(end -0.508 -0.9398)
			(stroke
				(width 0.1524)
				(type default)
			)
			(layer "F.SilkS")
		)
		(fp_line
			(start -0.508 -0.9398)
			(end -0.508 0.9398)
			(stroke
				(width 0.1524)
				(type default)
			)
			(layer "F.SilkS")
		)
		(fp_rect
			(start -0.508 0.9398)
			(end 0.508 -0.9398)
			(stroke
				(width 0)
				(type default)
			)
			(fill no)
			(layer "F.CrtYd")
		)
		(fp_rect
			(start -0.508 0.9398)
			(end 0.508 -0.9398)
			(stroke
				(width 0)
				(type default)
			)
			(fill no)
			(layer "F.Fab")
		)
		(pad "1" smd custom
			(at 0 -0.4445 90)
			(size 0.1397 0.1397)
			(layers "F.Cu" "F.Mask" "F.Paste")
			(net "GND")
			(options
				(clearance outline)
				(anchor circle)
			)
			(primitives
				(gr_poly
					(pts
						(arc
							(start -0.1778 -0.2794)
							(mid -0.249642 -0.249642)
							(end -0.2794 -0.1778)
						)
						(arc
							(start -0.2794 0.1778)
							(mid -0.249642 0.249642)
							(end -0.1778 0.2794)
						)
						(arc
							(start 0.1778 0.2794)
							(mid 0.249642 0.249642)
							(end 0.2794 0.1778)
						)
						(arc
							(start 0.2794 -0.1778)
							(mid 0.249642 -0.249642)
							(end 0.1778 -0.2794)
						)
					)
					(width 0)
					(fill yes)
				)
			)
		)
		(pad "2" smd custom
			(at 0 0.4445 90)
			(size 0.1397 0.1397)
			(layers "F.Cu" "F.Mask" "F.Paste")
			(net "MEMWEN")
			(options
				(clearance outline)
				(anchor circle)
			)
			(primitives
				(gr_poly
					(pts
						(arc
							(start -0.1778 -0.2794)
							(mid -0.249642 -0.249642)
							(end -0.2794 -0.1778)
						)
						(arc
							(start -0.2794 0.1778)
							(mid -0.249642 0.249642)
							(end -0.1778 0.2794)
						)
						(arc
							(start 0.1778 0.2794)
							(mid 0.249642 0.249642)
							(end 0.2794 0.1778)
						)
						(arc
							(start 0.2794 -0.1778)
							(mid 0.249642 -0.249642)
							(end 0.1778 -0.2794)
						)
					)
					(width 0)
					(fill yes)
				)
			)
		)
	)
	(footprint ""
		(layer "F.Cu")
		(at 40.4368 -158.30296)
		(property "Reference" "TP189"
			(at 0 0 0)
			(layer "F.SilkS")
			(hide yes)
			(effects
				(font
					(size 1.27 1.27)
				)
			)
		)
		(property "Value" "TPAD28-2-GP"
			(at -0.0127 -1.6637 0)
			(unlocked yes)
			(layer "F.Fab")
			(hide yes)
			(effects
				(font
					(size 1.016 1.016)
					(thickness 0.1524)
				)
			)
		)
		(property "Device Type" "TPAD28"
			(at -0.0127 -3.1877 0)
			(unlocked yes)
			(layer "F.Fab")
			(hide yes)
			(effects
				(font
					(size 1.016 1.016)
					(thickness 0.1524)
				)
			)
		)
		(duplicate_pad_numbers_are_jumpers no)
		(fp_poly
			(pts
				(arc
					(start 0.3556 0)
					(mid -0.3556 0)
					(end 0.3556 0)
				)
			)
			(stroke
				(width 0)
				(type default)
			)
			(fill no)
			(layer "F.CrtYd")
		)
		(fp_poly
			(pts
				(arc
					(start 0.6096 0)
					(mid -0.6096 0)
					(end 0.6096 0)
				)
			)
			(stroke
				(width 0)
				(type default)
			)
			(fill no)
			(layer "F.Fab")
		)
		(pad "1" smd circle
			(at 0 0)
			(size 0.7112 0.7112)
			(layers "F.Cu" "F.Mask" "F.Paste")
			(net "TP_BMC_GPIOL3")
		)
	)
	(footprint ""
		(layer "F.Cu")
		(at 180.921406 -107.418886)
		(property "Reference" "L11"
			(at 0 0 0)
			(layer "F.SilkS")
			(hide yes)
			(effects
				(font
					(size 1.27 1.27)
				)
			)
		)
		(property "Value" "BLM41PG600-GP"
			(at -3.690874 -7.441184 0)
			(unlocked yes)
			(layer "F.Fab")
			(hide yes)
			(effects
				(font
					(size 1.016 1.016)
					(thickness 0.1524)
				)
			)
		)
		(property "Device Type" "L451616H71"
			(at -3.690874 -5.917184 0)
			(unlocked yes)
			(layer "F.Fab")
			(hide yes)
			(effects
				(font
					(size 1.016 1.016)
					(thickness 0.1524)
				)
			)
		)
		(duplicate_pad_numbers_are_jumpers no)
		(fp_line
			(start -2.8702 -1.2954)
			(end -2.8702 1.2954)
			(stroke
				(width 0.1524)
				(type default)
			)
			(layer "F.SilkS")
		)
		(fp_line
			(start -2.8702 -1.2954)
			(end -2.8702 1.2954)
			(stroke
				(width 0.1524)
				(type default)
			)
			(layer "F.SilkS")
		)
		(fp_line
			(start -2.8702 1.2954)
			(end 2.8702 1.2954)
			(stroke
				(width 0.1524)
				(type default)
			)
			(layer "F.SilkS")
		)
		(fp_line
			(start -2.8702 1.2954)
			(end 2.8702 1.2954)
			(stroke
				(width 0.1524)
				(type default)
			)
			(layer "F.SilkS")
		)
		(fp_line
			(start 2.8702 -1.2954)
			(end -2.8702 -1.2954)
			(stroke
				(width 0.1524)
				(type default)
			)
			(layer "F.SilkS")
		)
		(fp_line
			(start 2.8702 -1.2954)
			(end -2.8702 -1.2954)
			(stroke
				(width 0.1524)
				(type default)
			)
			(layer "F.SilkS")
		)
		(fp_line
			(start 2.8702 1.2954)
			(end 2.8702 -1.2954)
			(stroke
				(width 0.1524)
				(type default)
			)
			(layer "F.SilkS")
		)
		(fp_line
			(start 2.8702 1.2954)
			(end 2.8702 -1.2954)
			(stroke
				(width 0.1524)
				(type default)
			)
			(layer "F.SilkS")
		)
		(fp_poly
			(pts
				(xy -2.8702 1.2954) (xy 2.8702 1.2954) (xy 2.8702 -1.2954) (xy -2.8702 -1.2954)
			)
			(stroke
				(width 0)
				(type default)
			)
			(fill no)
			(layer "F.CrtYd")
		)
		(fp_poly
			(pts
				(xy -2.8702 1.2954) (xy 2.8702 1.2954) (xy 2.8702 -1.2954) (xy -2.8702 -1.2954)
			)
			(stroke
				(width 0)
				(type default)
			)
			(fill no)
			(layer "F.Fab")
		)
		(pad "1" smd rect
			(at -1.9685 0)
			(size 1.3716 1.8796)
			(layers "F.Cu" "F.Mask" "F.Paste")
			(net "P12V_STBY")
		)
		(pad "2" smd rect
			(at 1.9685 0)
			(size 1.3716 1.8796)
			(layers "F.Cu" "F.Mask" "F.Paste")
			(net "VT235_VDDH")
		)
	)
	(footprint ""
		(layer "F.Cu")
		(at 17.723612 -131.007358 180)
		(property "Reference" "R221"
			(at 0 0 180)
			(layer "F.SilkS")
			(hide yes)
			(effects
				(font
					(size 1.27 1.27)
				)
			)
		)
		(property "Value" "120R2F-GP"
			(at 0.064008 -3.993896 180)
			(unlocked yes)
			(layer "F.Fab")
			(hide yes)
			(effects
				(font
					(size 1.016 1.016)
					(thickness 0.1524)
				)
			)
		)
		(property "Device Type" "R402H16"
			(at 0.064008 -5.517896 180)
			(unlocked yes)
			(layer "F.Fab")
			(hide yes)
			(effects
				(font
					(size 1.016 1.016)
					(thickness 0.1524)
				)
			)
		)
		(duplicate_pad_numbers_are_jumpers no)
		(fp_line
			(start 0.508 -0.9398)
			(end -0.508 -0.9398)
			(stroke
				(width 0.1524)
				(type default)
			)
			(layer "F.SilkS")
		)
		(fp_line
			(start -0.508 -0.9398)
			(end -0.508 0.9398)
			(stroke
				(width 0.1524)
				(type default)
			)
			(layer "F.SilkS")
		)
		(fp_rect
			(start -0.508 0.9398)
			(end 0.508 -0.9398)
			(stroke
				(width 0)
				(type default)
			)
			(fill no)
			(layer "F.CrtYd")
		)
		(fp_rect
			(start -0.508 0.9398)
			(end 0.508 -0.9398)
			(stroke
				(width 0)
				(type default)
			)
			(fill no)
			(layer "F.Fab")
		)
		(pad "1" smd custom
			(at 0 -0.4445 180)
			(size 0.1397 0.1397)
			(layers "F.Cu" "F.Mask" "F.Paste")
			(net "DDR4_ACT")
			(options
				(clearance outline)
				(anchor circle)
			)
			(primitives
				(gr_poly
					(pts
						(arc
							(start -0.1778 -0.2794)
							(mid -0.249642 -0.249642)
							(end -0.2794 -0.1778)
						)
						(arc
							(start -0.2794 0.1778)
							(mid -0.249642 0.249642)
							(end -0.1778 0.2794)
						)
						(arc
							(start 0.1778 0.2794)
							(mid 0.249642 0.249642)
							(end 0.2794 0.1778)
						)
						(arc
							(start 0.2794 -0.1778)
							(mid 0.249642 -0.249642)
							(end 0.1778 -0.2794)
						)
					)
					(width 0)
					(fill yes)
				)
			)
		)
		(pad "2" smd custom
			(at 0 0.4445 180)
			(size 0.1397 0.1397)
			(layers "F.Cu" "F.Mask" "F.Paste")
			(net "P1V2_STBY")
			(options
				(clearance outline)
				(anchor circle)
			)
			(primitives
				(gr_poly
					(pts
						(arc
							(start -0.1778 -0.2794)
							(mid -0.249642 -0.249642)
							(end -0.2794 -0.1778)
						)
						(arc
							(start -0.2794 0.1778)
							(mid -0.249642 0.249642)
							(end -0.1778 0.2794)
						)
						(arc
							(start 0.1778 0.2794)
							(mid 0.249642 0.249642)
							(end 0.2794 0.1778)
						)
						(arc
							(start 0.2794 -0.1778)
							(mid 0.249642 -0.249642)
							(end 0.1778 -0.2794)
						)
					)
					(width 0)
					(fill yes)
				)
			)
		)
	)
	(footprint ""
		(layer "F.Cu")
		(at 96.266 -137.9728 -90)
		(property "Reference" "C51"
			(at 0 0 270)
			(layer "F.SilkS")
			(hide yes)
			(effects
				(font
					(size 1.27 1.27)
				)
			)
		)
		(property "Value" "SCD1U16V2KX-3GP"
			(at 1.1811 -2.7051 270)
			(unlocked yes)
			(layer "F.Fab")
			(hide yes)
			(effects
				(font
					(size 1.016 1.016)
					(thickness 0.1524)
				)
			)
		)
		(property "Device Type" "C402H22"
			(at 1.1811 -4.2291 270)
			(unlocked yes)
			(layer "F.Fab")
			(hide yes)
			(effects
				(font
					(size 1.016 1.016)
					(thickness 0.1524)
				)
			)
		)
		(duplicate_pad_numbers_are_jumpers no)
		(fp_rect
			(start -0.4318 0.9525)
			(end 0.4318 -0.9525)
			(stroke
				(width 0)
				(type default)
			)
			(fill no)
			(layer "F.CrtYd")
		)
		(fp_rect
			(start -0.4318 0.9525)
			(end 0.4318 -0.9525)
			(stroke
				(width 0)
				(type default)
			)
			(fill no)
			(layer "F.Fab")
		)
		(pad "1" smd custom
			(at 0 -0.4445 270)
			(size 0.1524 0.1524)
			(layers "F.Cu" "F.Mask" "F.Paste")
			(net "P3V3_STBY")
			(options
				(clearance outline)
				(anchor circle)
			)
			(primitives
				(gr_poly
					(pts
						(arc
							(start 0.3048 -0.2032)
							(mid 0.275042 -0.275042)
							(end 0.2032 -0.3048)
						)
						(arc
							(start -0.2032 -0.3048)
							(mid -0.275042 -0.275042)
							(end -0.3048 -0.2032)
						)
						(arc
							(start -0.3048 0.2032)
							(mid -0.275042 0.275042)
							(end -0.2032 0.3048)
						)
						(arc
							(start 0.2032 0.3048)
							(mid 0.275042 0.275042)
							(end 0.3048 0.2032)
						)
					)
					(width 0)
					(fill yes)
				)
			)
		)
		(pad "2" smd custom
			(at 0 0.4445 270)
			(size 0.1524 0.1524)
			(layers "F.Cu" "F.Mask" "F.Paste")
			(net "GND")
			(options
				(clearance outline)
				(anchor circle)
			)
			(primitives
				(gr_poly
					(pts
						(arc
							(start 0.3048 -0.2032)
							(mid 0.275042 -0.275042)
							(end 0.2032 -0.3048)
						)
						(arc
							(start -0.2032 -0.3048)
							(mid -0.275042 -0.275042)
							(end -0.3048 -0.2032)
						)
						(arc
							(start -0.3048 0.2032)
							(mid -0.275042 0.275042)
							(end -0.2032 0.3048)
						)
						(arc
							(start 0.2032 0.3048)
							(mid 0.275042 0.275042)
							(end 0.3048 0.2032)
						)
					)
					(width 0)
					(fill yes)
				)
			)
		)
	)
)
